# BASEBOARD_FAB2 (Tioga Pass) — schematic netlist excerpt (pin names and nets, part order shuffled) for the footprints in the layout excerpt that follows; sources: Cadence DE-HDL packaged netlist, KiCad conversion of Wiwynn_Tioga_Pass_MB.brd

C9W2  SC22P50V2JN-4GP  5%  pkg SMD-BCG  page 200 : \1\ = A_P12V_STBY_ADR_TRIGGER ; \2\ = AGND_HSC
R1M21  RES  1.00K 1% CHIP  pkg 0402  page 113 : A = P1V8_MCP_CPU0 ; B = JTAG_MCP_TRST_N

(kicad_pcb
	(version 20260206)
	(generator "pcbnew")
	(generator_version "10.0")
	(general
		(thickness 1.6)
		(legacy_teardrops no)
	)
	(paper "A4")
	(title_block
		(title "Wiwynn_Tioga_Pass_MB.brd")
		(comment 1 "Tioga Pass / footprints 2598-2599 of 4770")
	)
	(layers
		(0 "F.Cu" signal "TOP")
		(4 "In1.Cu" signal "L2GND")
		(6 "In2.Cu" signal "L3")
		(8 "In3.Cu" signal "L4GND")
		(10 "In4.Cu" signal "L5")
		(12 "In5.Cu" signal "L6GND")
		(14 "In6.Cu" signal "L7VCC")
		(16 "In7.Cu" signal "L8VCC")
		(18 "In8.Cu" signal "L9GND")
		(20 "In9.Cu" signal "L10")
		(22 "In10.Cu" signal "L11GND")
		(24 "In11.Cu" signal "L12")
		(26 "In12.Cu" signal "L13GND")
		(2 "B.Cu" signal "BOTTOM")
		(9 "F.Adhes" user "F.Adhesive")
		(11 "B.Adhes" user "B.Adhesive")
		(13 "F.Paste" user "Package Geometry/Pastemask Top")
		(15 "B.Paste" user "Package Geometry/Pastemask Bottom")
		(5 "F.SilkS" user "Ref Des/Silkscreen Top")
		(7 "B.SilkS" user "Ref Des/Silkscreen Bottom")
		(1 "F.Mask" user "Board Geometry/Soldermask Top")
		(3 "B.Mask" user "Board Geometry/Soldermask Bottom")
		(17 "Dwgs.User" user "User.Drawings")
		(19 "Cmts.User" user "User.Comments")
		(21 "Eco1.User" user "User.Eco1")
		(23 "Eco2.User" user "User.Eco2")
		(25 "Edge.Cuts" user "Board Geometry/Outline")
		(27 "Margin" user)
		(31 "F.CrtYd" user "Package Geometry/Place Bound Top")
		(29 "B.CrtYd" user "Package Geometry/Place Bound Bottom")
		(35 "F.Fab" user "Ref Des/Assembly Top")
		(33 "B.Fab" user "Ref Des/Assembly Bottom")
	)
	(footprint ""
		(layer "B.Cu")
		(at 16.383 -90.805)
		(property "Reference" "C9W2"
			(at 0 0 0)
			(layer "B.SilkS")
			(hide yes)
			(effects
				(font
					(size 1.27 1.27)
				)
				(justify mirror)
			)
		)
		(property "Value" "*"
			(at -1.1811 -2.8194 0)
			(unlocked yes)
			(layer "B.Fab")
			(hide yes)
			(effects
				(font
					(size 1.27 1.016)
					(thickness 0.1524)
				)
				(justify mirror)
			)
		)
		(property "Device Type" "SC22P50V2JN-4GP_SMD-BCG-SC22P5A"
			(at -1.1811 -4.3434 0)
			(unlocked yes)
			(layer "B.Fab")
			(hide yes)
			(effects
				(font
					(size 1.27 1.016)
					(thickness 0.1524)
				)
				(justify mirror)
			)
		)
		(duplicate_pad_numbers_are_jumpers no)
		(fp_rect
			(start 0.4318 0.9525)
			(end -0.4318 -0.9525)
			(stroke
				(width 0)
				(type default)
			)
			(fill no)
			(layer "B.CrtYd")
		)
		(fp_rect
			(start 0.4318 0.9525)
			(end -0.4318 -0.9525)
			(stroke
				(width 0)
				(type default)
			)
			(fill no)
			(layer "B.Fab")
		)
		(pad "1" smd custom
			(at 0 -0.4445 180)
			(size 0.1524 0.1524)
			(layers "B.Cu" "B.Mask" "B.Paste")
			(net "A_P12V_STBY_ADR_TRIGGER")
			(options
				(clearance outline)
				(anchor circle)
			)
			(primitives
				(gr_poly
					(pts
						(arc
							(start 0.3048 0.2032)
							(mid 0.275042 0.275042)
							(end 0.2032 0.3048)
						)
						(arc
							(start -0.2032 0.3048)
							(mid -0.275042 0.275042)
							(end -0.3048 0.2032)
						)
						(arc
							(start -0.3048 -0.2032)
							(mid -0.275042 -0.275042)
							(end -0.2032 -0.3048)
						)
						(arc
							(start 0.2032 -0.3048)
							(mid 0.275042 -0.275042)
							(end 0.3048 -0.2032)
						)
					)
					(width 0)
					(fill yes)
				)
			)
		)
		(pad "2" smd custom
			(at 0 0.4445 180)
			(size 0.1524 0.1524)
			(layers "B.Cu" "B.Mask" "B.Paste")
			(net "AGND_HSC")
			(options
				(clearance outline)
				(anchor circle)
			)
			(primitives
				(gr_poly
					(pts
						(arc
							(start 0.3048 0.2032)
							(mid 0.275042 0.275042)
							(end 0.2032 0.3048)
						)
						(arc
							(start -0.2032 0.3048)
							(mid -0.275042 0.275042)
							(end -0.3048 0.2032)
						)
						(arc
							(start -0.3048 -0.2032)
							(mid -0.275042 -0.275042)
							(end -0.2032 -0.3048)
						)
						(arc
							(start 0.2032 -0.3048)
							(mid 0.275042 -0.275042)
							(end 0.3048 -0.2032)
						)
					)
					(width 0)
					(fill yes)
				)
			)
		)
	)
	(footprint ""
		(layer "B.Cu")
		(at 471.95486 -130.0734)
		(property "Reference" "R1M21"
			(at 0 0 0)
			(layer "B.SilkS")
			(hide yes)
			(effects
				(font
					(size 1.27 1.27)
				)
				(justify mirror)
			)
		)
		(property "Value" ""
			(at 0 0 0)
			(layer "B.Fab")
			(effects
				(font
					(size 1.27 1.27)
				)
				(justify mirror)
			)
		)
		(duplicate_pad_numbers_are_jumpers no)
		(fp_poly
			(pts
				(xy 0.2794 -0.1016) (xy -0.2794 -0.1016) (xy -0.2794 0.9906) (xy 0.2794 0.9906)
			)
			(stroke
				(width 0)
				(type default)
			)
			(fill no)
			(layer "B.CrtYd")
		)
		(fp_line
			(start -0.2794 -0.1016)
			(end 0.2794 -0.1016)
			(stroke
				(width 0.1)
				(type default)
			)
			(layer "B.Fab")
		)
		(fp_line
			(start -0.2794 0.9906)
			(end -0.2794 -0.1016)
			(stroke
				(width 0.1)
				(type default)
			)
			(layer "B.Fab")
		)
		(fp_line
			(start 0.2794 -0.1016)
			(end 0.2794 0.9906)
			(stroke
				(width 0.1)
				(type default)
			)
			(layer "B.Fab")
		)
		(fp_line
			(start 0.2794 0.9906)
			(end -0.2794 0.9906)
			(stroke
				(width 0.1)
				(type default)
			)
			(layer "B.Fab")
		)
		(pad "1" smd rect
			(at 0 0 180)
			(size 0.508 0.508)
			(layers "B.Cu" "B.Mask" "B.Paste")
			(net "P1V8_MCP_CPU0")
		)
		(pad "2" smd rect
			(at 0 0.889 180)
			(size 0.508 0.508)
			(layers "B.Cu" "B.Mask" "B.Paste")
			(net "JTAG_MCP_TRST_N")
		)
		(zone
			(layer "B.Cu")
			(hatch none 0.5)
			(connect_pads
				(clearance 0)
			)
			(min_thickness 0.25)
			(keepout
				(tracks allowed)
				(vias not_allowed)
				(pads allowed)
				(copperpour not_allowed)
				(footprints allowed)
			)
			(placement
				(enabled no)
				(sheetname "")
			)
			(fill
				(thermal_gap 0.5)
				(thermal_bridge_width 0.5)
				(island_removal_mode 0)
			)
			(polygon
				(pts
					(xy 472.20886 -129.8194) (xy 471.70086 -129.8194) (xy 471.70086 -129.4384) (xy 472.20886 -129.4384)
				)
			)
		)
		(zone
			(layer "B.Cu")
			(hatch none 0.5)
			(connect_pads
				(clearance 0)
			)
			(min_thickness 0.25)
			(keepout
				(tracks not_allowed)
				(vias allowed)
				(pads allowed)
				(copperpour not_allowed)
				(footprints allowed)
			)
			(placement
				(enabled no)
				(sheetname "")
			)
			(fill
				(thermal_gap 0.5)
				(thermal_bridge_width 0.5)
				(island_removal_mode 0)
			)
			(polygon
				(pts
					(xy 472.20886 -129.4384) (xy 471.70086 -129.4384) (xy 471.70086 -129.8194) (xy 472.20886 -129.8194)
				)
			)
		)
	)
)
